M48
;Layer_Color=9474304
;FILE_FORMAT=2:5
INCH,LZ
;TYPE=PLATED
T1F00S00C0.00787
T2F00S00C0.00800
T4F00S00C0.02166
T6F00S00C0.02800
T7F00S00C0.02992
T8F00S00C0.03543
T9F00S00C0.04016
T10F00S00C0.05906
T11F00S00C0.06693
T12F00S00C0.07087
T13F00S00C0.07900
T14F00S00C0.11811
T15F00S00C0.12200
T16F00S00C0.12520
;TYPE=NON_PLATED
T17F00S00C0.06598
T18F00S00C0.10000
T19F00S00C0.11800
T20F00S00C0.12520
%
T01
X0099016Y-0130315
Y-0125984
Y-0121653
X0103347
X0107677
Y-0125984
X0103347
Y-0130315
X0107677
T02
X0634252Y-0314567
X063975Y-0314581
X065315Y-0314567
X0658647Y-0314581
X0664966Y-0316582
X0664961Y-0325984
X0692126Y-0322441
X0692037Y-0315878
X0683858Y-031063
X0683716Y-0298538
X0678346Y-0297244
X0678441Y-0292586
X0637795Y-0297638
X0627559Y-0296457
X0612598Y-0291732
X0615748Y-0305512
X0588976Y-0302756
X0579528Y-030315
X0582874Y-0294291
X0595276Y-0291732
X0565354Y-0292913
X0554724Y-0294882
X0545276Y-0294094
X0562598Y-0306693
X0509011Y-0330177
X0508997Y-0335675
X0509405Y-0345138
X0509391Y-0350636
X0461811Y-0327165
X046063Y-0324852
X045748
X0456693Y-0327165
X0454724
X0453937Y-0324852
X0451181
X0450394Y-0327165
X0448032
X0447244Y-0324852
X0444488
X0443701Y-0327165
X0441732
X0440551Y-0324852
X0437795
X0436614Y-0327165
X0434646Y-0327559
X0433858Y-0324852
X0431102
X0429528Y-0326772
X0431928Y-0311189
X0431102Y-0308268
X0433465Y-0306742
X0436221
X0437048Y-0308863
X043937Y-0306742
X0442126
X0445276
X0448032
X0448819Y-0309055
X0451575
X0451181Y-0306742
X0453937
X045748Y-0306693
X0461811Y-0310679
X0461417Y-029375
X0456299
X045
X0444095
X0437795Y-029375
X0432283Y-029375
X0422441Y-0293789
X0412205Y-029375
X0402362Y-029375
X0402756Y-0311072
X0412598
X0422835
X0444507Y-0309009
X0273425Y-0374655
X0269502Y-0374291
X025689Y-0374655
X0253655Y-0374421
X0241929Y-0374655
X0237992
X0222638
X0218445Y-0374108
X0210433Y-0374655
X0206496
X0196701Y-0370523
X0198392Y-0366842
X0190354Y-0377411
X0178543
X0179134Y-0386466
Y-0389616
X0182677
Y-0386466
X0186614
Y-0389616
X0174941Y-03906
X0163071Y-039073
X0158661Y-0389616
X0156693
X0154724
Y-0386466
X0156693
X0158661
X015748Y-0361811
X0155512
Y-0358661
X015748
X0202441Y-03906
X0212795Y-0387253
X0215945
X0216162Y-0390947
X0226063Y-0390722
X0229331Y-0387253
X023248
X0235144Y-0390416
X0246339Y-0386975
X024941Y-0387253
X0251456Y-0390009
X0259285Y-0390247
X0262006Y-0387255
X0265158Y-0387253
X0267204Y-0390009
X0281201
X0153543Y-0361811
Y-0358661
X0141981Y-0347043
X014252Y-0342913
X0087598Y-033563
Y-0329724
X008563Y-0320313
X0085416Y-0317699
X008563Y-0313976
X0056441Y-03116
X0052441
X0054441Y-03076
X0056441Y-03036
X0052441
X0048441
X0050441Y-02996
X0054441
Y-02916
X0050441
X0046441
Y-02996
X0042441
X0034441
Y-03076
X0026441
X0022441
X0018441
X0014441
X0016441Y-03036
X0020441
X0024441
X0026441Y-02996
X0022441
X0018441
X0014441
X0010441
X0012441Y-03036
Y-03116
X0016441
X0020441
X0024441
X0022441Y-03236
X0018441
X0014441
X0010441
X0012441Y-03276
X0016441
X0014441Y-03316
X0010441
X0020441Y-03356
X0024441
X0028441
X0032441
X0036441
X0040441
X0044441
X0048441
X0052441
X0056441
X0054441Y-03316
X0050441
X0046441
X0042441
X0038441
X0034441
X0030441
X0026441
X0028441Y-03276
X0032441
X0036441
X0034441Y-03236
X0044291Y-0326772
X0052441Y-03276
X0056441
X0054441Y-03236
X0062992Y-0329724
X0067913Y-0340551
X0074803Y-0339567
X007874Y-0340551
X0054441Y-03396
X0050441
X0046441
X0042441
X0038441
X0034441
X0030441
X0026441
X0022441
X0018441
X0020441Y-03436
X0024441
X0028441
X0032441
X0036441
X0040441
X0044441
X0048441
X0052441
X0056441
Y-03516
X0052441
X0048441
X0044441
X0040441
X0036441
X0032441
X0028441
X0024441
X0020441
X0016441
X0012441
X0008441
X0004441
X0000441
X0012441Y-03436
X0016441
X0018441Y-02916
X0022441
X0026575Y-0291339
X0014441Y-02916
X0044291Y-0307087
X-0007559Y-03036
X-0005559Y-02996
X-0009559
X-0025559
X-0023622Y-0294291
X-0025559Y-03156
X-0021559
X-0023622Y-033563
Y-0339567
Y-034252
Y-0346457
X-0023559Y-03516
X-0019559
X-0015559
X-0011559
X-0007559
X-0003559
X-0009559Y-03316
X-0007559Y-03276
Y-02796
X-0011559
X-0009559Y-02756
X-0023622Y-028248
Y-0286417
Y-0290354
X-0025559Y-02676
X-0023559Y-02636
X-0019559
X-0025559Y-02596
X-0023622Y-0241142
Y-0237205
Y-0233268
Y-0229331
X-0009559Y-02276
X-0005559
X-0007559Y-02236
X-0005559Y-02436
X-0009559
X-0013559
X-0011559Y-02476
X-0007559
X-0009559Y-02516
X-0021559Y-02116
X-0025559
X-0023559Y-01916
X-0023622Y-0187992
Y-0184055
Y-0181102
Y-0177165
X-0023559Y-01596
X-0025559Y-01556
Y-01396
X-0013559
X-0009559
X-0005559
X-0007559Y-01436
Y-01676
X-0009559Y-01716
X-0007559Y-01916
X-0003559
X-0011559
X-0015559
X-0009559Y-01956
X-0007559Y-01996
X0012441
X0016441
X0020441
X0022441Y-01956
X0026441
X0024441Y-01916
X0020441
X0016441
X0012441
X0008441
X0004441
X0010441Y-01956
X0014441
X0018441
Y-02036
X0014441
X0010441
X0012441Y-02156
X0016441
X0018441Y-02196
X0014441
X0016441Y-02236
X0012441
X0010441Y-02276
X0020441Y-02316
X0022441Y-02356
X0018441
Y-02436
X0022441
X0020441Y-02476
X0016441
X0012441
X0008441
X0010441Y-02436
X0014441
Y-02516
X0018441
X0022441
X0020441Y-02556
X0016441
X0012441
X0014441Y-02596
X0018441
X0022441
Y-02676
X0018441
X0014441
X0010441
X0012441Y-02716
X0016441
X0020441
X0018441Y-02756
X0014441
X0010441
X0012441Y-02796
X0016441
X0008441
X0022441Y-02836
X0026575Y-0283465
X0024441Y-02876
X0020441
X0044441
X0048441
X0052441
X0056441
Y-02796
X0052441
X0048441
X0044441
X0044291Y-0272638
X0050441Y-02756
X0054441
X0056441Y-02716
X0052441
X0054441Y-02676
X0056441Y-02556
X0052441
X0054441Y-02516
X0050441
X0052441Y-02476
X0056441
X0054441Y-02436
X0050441
X0046441
X0042441
X0038441
X0034441
X0036441Y-02476
X0040441
X0044441
X0048441
X0044291Y-0252953
X0038441Y-02516
X0034441
X0036441Y-02556
X0034441Y-02676
Y-02756
X0063976Y-027559
X0068898Y-0285433
X0075787
X008188Y-0287582
X0087598Y-0281496
Y-027559
X008563Y-0266179
Y-0263779
X0086614Y-0258858
X0106299Y-0263632
X0120079Y-0263386
X007874Y-0238041
X0075787Y-0232283
X0082677
X0086614Y-0227362
Y-0221457
X008563Y-0213583
X0086562Y-0211183
X0081693Y-0205709
X0080709Y-0180118
X0074803Y-0179134
X0068573Y-0179321
X0063976Y-0179134
X0056441Y-01916
X0052441
X0054441Y-01956
X0050441
X0052441Y-01996
X0056441
X0054441Y-02036
X0048441Y-01996
X0044291Y-0200787
Y-0220472
X0040441Y-02236
X0036441
X0038441Y-02276
X0042441
X0046441
X0050441
X0054441
X0056441Y-02236
X0052441
X0048441
Y-02316
X0052441
X0056441
X0054441Y-02356
X0050441
X0046441
X0042441
X0038441
X0034441
X0036441Y-02316
X0040441
X0044441
X0034441Y-02276
Y-02196
X0036441Y-02156
X0052441
X0056441
X0054441Y-02196
X0063976Y-0221457
Y-0227362
X0097125Y-0219488
X009941Y-0216535
X0101378Y-0214567
X0102528Y-0211583
X0086614Y-0175197
X0086562Y-0169257
X0087167Y-0166377
X0089567Y-016637
X0089567Y-014027
X0087254Y-0139629
X0097409Y-0140111
X009941Y-0141732
X0101409Y-0140111
X0103409Y-0141732
X0105409Y-0140111
X0107409Y-0141732
X0109409Y-0140111
X007185Y-0147638
X0054441Y-01476
X0056441Y-01436
X0052441
X0048441
X0044441
X0040441
X0036441
X0032441
X0028441
X0024441
X0020441
X0016441
X0012441
X0014441Y-01396
X0018441
X0022441
X0026441
X0030441
X0034441
X0038441
X0042441
X0046441
X0050441
X0054441
X0056441Y-01516
X0052441
X0044291Y-0147638
X0034441Y-01476
X0030441
X0026441
X0022441
X0018441
X0014441
X0016441Y-01516
X0020441
X0024441
X0028441
X0032441
X0036441
X0034441Y-01636
X0030441
X0026441
X0022441
X0018441
X0014441
X0010441
X0012441Y-01676
X0016441
X0020441
X0024441
X0028441
X0030512Y-0170276
X0022441Y-01716
X0018441
X0014441
X0010441
X0012441Y-01516
X0010441Y-01396
X0006441
X0044291Y-0167323
X0031496Y-0189961
X0006441Y-02436
X0002441
X-0001559
X0010441Y-02516
Y-02596
X0288189Y-0247638
X0288057Y-0245095
X0287941Y-0241819
X0288189Y-0235827
X0288057Y-0233478
X0288189Y-0231102
Y-022874
X0288583Y-022559
X0314503Y-022518
X0314417Y-0228033
X0314623Y-0231391
X0315097Y-0235081
X0314658Y-0244775
X0325787Y-0243205
X032385Y-0241173
X0325787Y-0239205
X032385Y-0237205
X0325787Y-0233362
Y-0229362
X0323819Y-0231299
Y-0227362
X0338444Y-0225173
X0343144
X0343444Y-0215373
X0338844Y-0215273
X0338744Y-0205473
X0343403Y-0205651
X0361811Y-0207087
X0361417Y-020315
X0366535Y-0202362
X0372016Y-0200787
X0377921Y-020374
X0379921Y-020174
X0358661Y-0194488
X0359131Y-0223425
X0361531
X0356578Y-0225247
X0354541Y-0223636
X0354452Y-0235236
X0356852
X0359252
X0361652Y-0235205
X0343504Y-0235236
X0338583
X0338525Y-0243567
X0342744Y-0243747
X0343144Y-0254773
X0338444
Y-0264473
X0342944
X0360236Y-0266186
Y-0268586
Y-027249
Y-0262186
X0360204Y-0252984
X0325984Y-0272441
X0326969Y-0197573
X0326966Y-0195171
X0411811Y-019685
X0416835Y-0196581
X0417596Y-0175197
X0421596Y-0175034
X0423461Y-0178869
X0427165Y-0175246
X0430807Y-0175344
X0433858Y-0175246
X0437697
X0443898Y-0175049
X045085Y-0174127
X0457283Y-0175147
X0460186Y-0175448
X0459319Y-016251
Y-0157922
X0449803Y-0157923
X0449508Y-0162549
X0439697
X0439961Y-0157923
X043015
Y-0162253
X0420079Y-0162549
X0420669Y-0157923
X0410528
X0406528Y-0157767
X040748Y-0160433
Y-0163386
X0404528
X0401279Y-0162509
X0400295Y-0157824
X0398568Y-0145083
X0416106Y-014418
X0418898Y-0144143
X0414567Y-0137402
X04099Y-0136559
X0430492Y-0136473
X0436614Y-0136614
X0461319Y-014375
X0464328Y-0146397
X0410913Y-0162758
X0411043Y-0174974
X041344Y-017485
X0404823Y-0175344
X0402264
X0381496Y-0140945
X038189Y-0137402
X0379134Y-0137795
X0377559Y-0135433
Y-0142126
X0469291Y-0143848
X0469521Y-0137615
X046939Y-0175147
X0474016Y-0176378
X0476945Y-0173228
X0499111Y-0179528
X0498819Y-0183858
X0498693Y-0188351
X0509842Y-0195718
Y-0197687
Y-0199655
Y-0201624
X0525591Y-0203592
X0531496
Y-0213435
X0525591
Y-0223277
X0531496
Y-0233088
X0525591
Y-0242962
X0531496
Y-0253969
X0525591
Y-0262647
X0531496
X0544488Y-0265748
X0545276Y-0270866
Y-0275197
X0545128Y-0280872
X0544909Y-0287437
X0569548Y-0287223
X056811Y-0284252
X0571162Y-0284136
X0574803Y-0284252
X0577953Y-0284646
Y-025748
X0581496
X0585433
Y-0253937
X0585039Y-0249606
X0590551Y-024252
X0586537Y-0234843
X0586221Y-0226772
X0590158Y-0226378
X0579921Y-0227559
X0576772Y-022874
X0572441Y-0227165
X0555512Y-0218504
X0554724Y-0207874
X0549213
X0547244Y-020315
X0544291Y-0201624
Y-0199655
Y-0197687
Y-0195718
X0548819Y-0196063
X0549298Y-0191988
X0548093Y-0185219
X0548425Y-018189
X0548819Y-017874
X0533044Y-0176225
X0530027Y-0172987
X0515702Y-0162803
X0518337Y-0159634
X0519587Y-0134596
X0524409Y-0135827
X05399Y-0140766
X0547244Y-0144488
Y-0157087
X0570472Y-0137795
X0584646Y-017874
X0589764Y-0179134
X0594882
X0599564Y-017894
X0598425Y-0198819
X0595276
X0592126
X0589764
X0587008
X0581496
X0577953
X0573622
X0570079Y-02
X0569291Y-0194095
X0574803Y-0195276
X0579134
X054685Y-0213779
X0544291Y-0215403
X0544294Y-0224248
X0543276Y-0226591
X0544291Y-0233268
X0545669Y-0253937
X0548425Y-0253543
X0556628Y-0258042
X0557087Y-0261417
X0559842Y-0257087
X0563386Y-0257874
X0566535Y-0255906
X0570079
X0572441Y-0258268
X0567717Y-0259055
X0588189Y-0263386
X0590551Y-0266535
X06Y-0248425
X0605118Y-0244488
X0608661Y-0242126
Y-0236221
X0611417Y-0247638
X0612205Y-0251575
X0616535Y-0255512
X0512402Y-0261958
Y-0265108
X0512543Y-0268065
X0512657Y-0270462
X0500394Y-0222835
X0495669Y-0222047
X0635039Y-0216142
X0652756Y-0218504
X065Y-0231102
X0646434Y-0231245
X0637008Y-0238583
X0624409Y-0248031
X0624803Y-0251575
Y-0255906
X0630577Y-0278001
X0639764Y-0283858
X0646457
X065
X0654331
X0652362Y-0279528
X0648819Y-027874
X0651575Y-0275197
X0657087Y-0279528
X067126Y-027874
Y-0274803
X0671654Y-0283071
X0676772Y-0270866
X0676378Y-0266142
X0673622Y-0261417
X0672835Y-0257087
X0673228Y-0251181
X0671654Y-0217323
X0669685Y-0213779
X0673622
X0666142Y-0212992
X0680709Y-0212205
Y-0216929
X068189Y-02
X067874
Y-019685
X068189
X0675591Y-0196457
X0675197Y-02
X0681496Y-0179528
X0677165Y-0172441
X0673228
X0668504Y-0164961
X0662992
X065748Y-0164567
X0652756Y-0164961
X0644619Y-0166285
X0644569Y-016291
X0644488Y-0159843
X0646457Y-0156693
X064252
X0644488Y-0170472
X0635433Y-0184252
X0635827Y-0187795
X0679921Y-0160236
X0684646Y-0161811
X068937Y-0161417
X0689764Y-0164567
Y-016811
X0667717Y-0106693
X0662539Y-0107066
X0666929Y-0098032
X0676378Y-0083858
X0675926Y-0072691
X0670538Y-0074409
X0668438
X0660719Y-0075726
X0658053Y-0071188
X0657445Y-0063525
X0658114Y-0056714
X0659449Y-0049213
X0658465Y-0037647
Y-0029773
Y-0021899
X0660236Y-0014961
X0670079Y-0009449
X0673228Y-0029528
X0679517Y-0026553
Y-0037023
X0675591Y-004252
X0671654Y-0041339
X0676772Y-0051575
Y-0054331
X0680082Y-0064183
X0683127Y-0066209
X0689466Y-0066165
X0694095Y-0062205
X0696762Y-0063288
X0696577Y-0051453
X0693977Y-0053201
X0686319Y-0043553
X0686728Y-0033442
X0693915Y-0033393
X0685716Y-0022157
X0671654Y-0062598
X0623511Y-0062552
X0623228Y-0055118
X0625Y-004808
X0623Y-0037402
X0625Y-0029773
Y-0021899
X0623622Y-0070866
X0631814Y-0083784
X0629101Y-0090137
X0623228Y-0093307
X0629134Y-0102756
X0620959Y-0100047
X0616929Y-01
X0612598
X0609055Y-009252
X0612205Y-0087008
X0616535Y-0084646
X0618898Y-0082284
X0599279Y-0082981
X0600394Y-0087795
X0601745Y-0098051
X059252Y-0093307
X0588976Y-0086221
X0577953Y-0083858
X0578168Y-0080778
X0574016Y-007441
Y-0072441
Y-0070472
X0570866
Y-0072441
Y-007441
X0568504Y-0088189
X0569291Y-0091339
X0567323Y-0094095
X0569092Y-0108048
X0579921Y-0101969
X0584763Y-0100116
X0588372Y-0100945
X0585433Y-0114961
X0584252Y-0117717
X0580315Y-0129921
X0579921Y-0133465
X0574409
X0570866
X0572047Y-0129921
X0576378
X0531801Y-0127495
X0524557Y-012874
X0524606Y-0125836
X0533878Y-0117716
X0539233Y-0115729
X0538583Y-0111811
X0546386Y-0109024
X0528543Y-0104214
X0518701
X0512795
X0504703Y-0106672
X0500313Y-0105734
X0501669Y-0116601
X0508268Y-0117323
X0505905Y-0123622
X0506207Y-0127333
X0506299Y-0129921
X0498032Y-0132283
X0488583
X048012Y-0132365
X0475984Y-0127165
X0476772Y-0123622
X0470472Y-0123622
X0469685Y-0133465
X0472441Y-0113779
X0473228Y-0105905
X0483484Y-010584
X0597227Y-0077103
X0596063Y-0053937
X0602756Y-0039764
X0614567Y-0044882
X0609252Y-0026575
X0610236Y-0008858
X0615158
X0463551Y-0116025
X0456742Y-0116043
X0443307Y-0111024
X0441929Y-0122883
X0435827Y-0103543
X0402719Y-0112334
X0383465Y-010748
X0380339Y-0107321
X0377165Y-0107283
X037874Y-0123622
X0375532Y-012361
X037559Y-0127165
X037874Y-0127165
X0381496
X0354724Y-0116929
X0352756
X0350787
Y-0113779
X0352756
X0354724
X0366929Y-008937
Y-0086614
Y-0083071
Y-0079528
Y-0075984
X0314961Y-0118947
X0309055Y-0123868
X0309016Y-0128659
Y-0113986
X0271654Y-0122835
X0267717Y-0123622
X0267323Y-0132677
X0272047Y-0131496
X0254376Y-0125747
X0255512Y-012126
X0255118Y-0118504
X025369Y-011196
X0253713Y-010919
X0256897Y-0112001
X0246063Y-0111024
X0244664Y-0106952
X0241077Y-0118805
X0238189Y-0116142
X024125Y-0126247
X0248425Y-0129134
X0234252Y-0133742
X0228824Y-010485
X0263779Y-0106151
X0269685
X0193898Y-0115009
Y-0119931
X0144871Y-0131609
X0119095Y-0130047
X0117126Y-0128047
X0119095Y-0126047
X0117126Y-0124047
X0119095Y-0122047
X0117126Y-0119921
Y-0132047
X0109409Y-0112236
X0107346Y-0110236
X0105347Y-0112205
X0103347Y-0110236
X0099347
X0101284Y-0112205
X0097284
X0098425Y-0102362
X0089567
X0084079Y-0105653
X0062986Y-0112803
X0062499Y-0117255
X0070866Y-0122047
X0075787Y-013189
X0104528Y-0092175
X0114173Y-0083088
X0129921Y-0079576
X013189Y-0072687
X009941Y-0065797
Y-0057923
Y-0050049
X0101575Y-0042126
X0111024Y-0033071
X0125591Y-0032283
X0101181Y-0018504
X0055905Y-0031496
X0043701Y-0029921
X0040354Y-0008858
X0047244
X0033465
X0026495Y-0008991
X0026575Y0019685
X0033465Y0019833
X0040354Y0019685
X0047244
X0064173Y-004252
X0065945Y-0050049
Y-0057923
Y-0065797
X-0023622Y-0066929
Y-0062992
Y-0060039
Y-0070866
Y-0102362
Y-0106299
Y-0110236
Y-0114173
T04
X0470275Y-0308597
X0391535
X0340904Y-027341
Y-019467
X0391545Y-0160477
X0470285
X0528395Y-019468
Y-027342
T06
X0348211Y-0089891
X0357798Y-0089963
T07
X064064Y-0065206
Y-003371
Y-0017962
X0082785Y-002249
Y-0053986
Y-0069734
T08
X0539055Y0003937
Y0013937
X0549055
X0559055
X0569055
X0579055
X0589055
Y0003937
X0579055
X0569055
X0559055
X0549055
T09
X0161496Y-0120079
X0171496
X0181496
X0151496
X0141496
T10
X-0008465Y-0316781
X-0008465Y-026363
Y-021048
X-0008465Y-0157332
T11
X0001535Y-0326781
Y-0306781
X-0018464
Y-0326781
X-0018465Y-027363
Y-025363
Y-022048
Y-020048
X-0018464Y-0167332
Y-0147332
X0001535
Y-0167332
X0001535Y-020048
Y-022048
Y-025363
Y-027363
T12
X0622001Y-0143945
X0643701
Y-0127445
X0622001
T13
X0246472Y-0327165
X0258472
X0270472
X0282283
X0294094
X0302362Y-0316535
X014252
Y-0236614
Y-0156693
X0302362
T14
X0533015Y-0312764
X0336515
X0336415Y-0155764
X0533015
T15
X0651545Y-0095108
Y0007254
X0413356
Y-0095108
X0310069Y-009495
Y0007412
X007188
Y-009495
T16
X0685039Y-0340551
X0486221Y-0340551
X0685039Y0
T17
X0574291Y-0330039
X0604291
T18
X016002Y-0314535
X0285128Y-0308632
X0284862Y-0164793
X016252Y-0152693
T19
X0672401Y-0135695
T20
X0Y-0378395
X0Y0
M30
